# BASEBOARD_FAB2 (Tioga Pass) — schematic netlist excerpt (pin names and nets, part order shuffled) for the footprints in the layout excerpt that follows; sources: Cadence DE-HDL packaged netlist, KiCad conversion of Wiwynn_Tioga_Pass_MB.brd

C8P7  CAP  22UF 4V 20% X6S  pkg 0805LF  page 76 : A = PVSA_CPU1 ; B = GND
R783  RES  0.0 5% CHIP  pkg 0402  page 244 : A = P3E_CPU0_PE1_PCH_RXP<9> ; B = P3E_CPU0_PE1_PCH_CON_RXP<9>
C9R12  CAP_A  0.1UF 16V 10% X7R  pkg 0402V  page 195 : A = P12V_PSU ; B = GND

(kicad_pcb
	(version 20260206)
	(generator "pcbnew")
	(generator_version "10.0")
	(general
		(thickness 1.6)
		(legacy_teardrops no)
	)
	(paper "A4")
	(title_block
		(title "Wiwynn_Tioga_Pass_MB.brd")
		(comment 1 "Tioga Pass / footprints 2721-2723 of 4770")
	)
	(layers
		(0 "F.Cu" signal "TOP")
		(4 "In1.Cu" signal "L2GND")
		(6 "In2.Cu" signal "L3")
		(8 "In3.Cu" signal "L4GND")
		(10 "In4.Cu" signal "L5")
		(12 "In5.Cu" signal "L6GND")
		(14 "In6.Cu" signal "L7VCC")
		(16 "In7.Cu" signal "L8VCC")
		(18 "In8.Cu" signal "L9GND")
		(20 "In9.Cu" signal "L10")
		(22 "In10.Cu" signal "L11GND")
		(24 "In11.Cu" signal "L12")
		(26 "In12.Cu" signal "L13GND")
		(2 "B.Cu" signal "BOTTOM")
		(9 "F.Adhes" user "F.Adhesive")
		(11 "B.Adhes" user "B.Adhesive")
		(13 "F.Paste" user "Package Geometry/Pastemask Top")
		(15 "B.Paste" user "Package Geometry/Pastemask Bottom")
		(5 "F.SilkS" user "Ref Des/Silkscreen Top")
		(7 "B.SilkS" user "Ref Des/Silkscreen Bottom")
		(1 "F.Mask" user "Board Geometry/Soldermask Top")
		(3 "B.Mask" user "Board Geometry/Soldermask Bottom")
		(17 "Dwgs.User" user "User.Drawings")
		(19 "Cmts.User" user "User.Comments")
		(21 "Eco1.User" user "User.Eco1")
		(23 "Eco2.User" user "User.Eco2")
		(25 "Edge.Cuts" user "Board Geometry/Outline")
		(27 "Margin" user)
		(31 "F.CrtYd" user "Package Geometry/Place Bound Top")
		(29 "B.CrtYd" user "Package Geometry/Place Bound Bottom")
		(35 "F.Fab" user "Ref Des/Assembly Top")
		(33 "B.Fab" user "Ref Des/Assembly Bottom")
	)
	(footprint ""
		(layer "B.Cu")
		(at 94.271592 -82.001614)
		(property "Reference" "C8P7"
			(at 0 0 0)
			(layer "B.SilkS")
			(hide yes)
			(effects
				(font
					(size 1.27 1.27)
				)
				(justify mirror)
			)
		)
		(property "Value" ""
			(at 0 0 0)
			(layer "B.Fab")
			(effects
				(font
					(size 1.27 1.27)
				)
				(justify mirror)
			)
		)
		(duplicate_pad_numbers_are_jumpers no)
		(fp_poly
			(pts
				(xy 0.7239 -0.2159) (xy -0.7239 -0.2159) (xy -0.7239 1.9939) (xy 0.7239 1.9939)
			)
			(stroke
				(width 0)
				(type default)
			)
			(fill no)
			(layer "B.CrtYd")
		)
		(fp_line
			(start -0.7239 -0.2159)
			(end 0.7239 -0.2159)
			(stroke
				(width 0.1)
				(type default)
			)
			(layer "B.Fab")
		)
		(fp_line
			(start -0.7239 1.9939)
			(end -0.7239 -0.2159)
			(stroke
				(width 0.1)
				(type default)
			)
			(layer "B.Fab")
		)
		(fp_line
			(start 0.7239 -0.2159)
			(end 0.7239 1.9939)
			(stroke
				(width 0.1)
				(type default)
			)
			(layer "B.Fab")
		)
		(fp_line
			(start 0.7239 1.9939)
			(end -0.7239 1.9939)
			(stroke
				(width 0.1)
				(type default)
			)
			(layer "B.Fab")
		)
		(pad "1" smd rect
			(at 0 0 180)
			(size 1.27 1.016)
			(layers "B.Cu" "B.Mask" "B.Paste")
			(net "PVSA_CPU1")
		)
		(pad "2" smd rect
			(at 0 1.778 180)
			(size 1.27 1.016)
			(layers "B.Cu" "B.Mask" "B.Paste")
			(net "GND")
		)
		(zone
			(layer "B.Cu")
			(hatch none 0.5)
			(connect_pads
				(clearance 0)
			)
			(min_thickness 0.25)
			(keepout
				(tracks not_allowed)
				(vias allowed)
				(pads allowed)
				(copperpour not_allowed)
				(footprints allowed)
			)
			(placement
				(enabled no)
				(sheetname "")
			)
			(fill
				(thermal_gap 0.5)
				(thermal_bridge_width 0.5)
				(island_removal_mode 0)
			)
			(polygon
				(pts
					(xy 94.906592 -81.493614) (xy 93.636592 -81.493614) (xy 93.636592 -80.731614) (xy 94.906592 -80.731614)
				)
			)
		)
	)
	(footprint ""
		(layer "B.Cu")
		(at 367.827814 -124.389642 -90)
		(property "Reference" "R783"
			(at 0.8382 -0.67818 270)
			(unlocked yes)
			(layer "B.SilkS")
			(effects
				(font
					(size 0.4064 0.254)
					(thickness 0.1524)
				)
				(justify left mirror)
			)
		)
		(property "Value" ""
			(at 0 0 90)
			(layer "B.Fab")
			(effects
				(font
					(size 1.27 1.27)
				)
				(justify mirror)
			)
		)
		(duplicate_pad_numbers_are_jumpers no)
		(fp_poly
			(pts
				(xy 0.2794 -0.1016) (xy -0.2794 -0.1016) (xy -0.2794 0.9906) (xy 0.2794 0.9906)
			)
			(stroke
				(width 0)
				(type default)
			)
			(fill no)
			(layer "B.CrtYd")
		)
		(fp_line
			(start -0.2794 0.9906)
			(end -0.2794 -0.1016)
			(stroke
				(width 0.1)
				(type default)
			)
			(layer "B.Fab")
		)
		(fp_line
			(start 0.2794 0.9906)
			(end -0.2794 0.9906)
			(stroke
				(width 0.1)
				(type default)
			)
			(layer "B.Fab")
		)
		(fp_line
			(start -0.2794 -0.1016)
			(end 0.2794 -0.1016)
			(stroke
				(width 0.1)
				(type default)
			)
			(layer "B.Fab")
		)
		(fp_line
			(start 0.2794 -0.1016)
			(end 0.2794 0.9906)
			(stroke
				(width 0.1)
				(type default)
			)
			(layer "B.Fab")
		)
		(pad "1" smd rect
			(at 0 0 90)
			(size 0.508 0.508)
			(layers "B.Cu" "B.Mask" "B.Paste")
			(net "P3E_CPU0_PE1_PCH_RXP<9>")
		)
		(pad "2" smd rect
			(at 0 0.889 90)
			(size 0.508 0.508)
			(layers "B.Cu" "B.Mask" "B.Paste")
			(net "P3E_CPU0_PE1_PCH_CON_RXP<9>")
		)
		(zone
			(layer "B.Cu")
			(hatch none 0.5)
			(connect_pads
				(clearance 0)
			)
			(min_thickness 0.25)
			(keepout
				(tracks not_allowed)
				(vias allowed)
				(pads allowed)
				(copperpour not_allowed)
				(footprints allowed)
			)
			(placement
				(enabled no)
				(sheetname "")
			)
			(fill
				(thermal_gap 0.5)
				(thermal_bridge_width 0.5)
				(island_removal_mode 0)
			)
			(polygon
				(pts
					(xy 367.192814 -124.135642) (xy 367.192814 -124.643642) (xy 367.573814 -124.643642) (xy 367.573814 -124.135642)
				)
			)
		)
		(zone
			(layer "B.Cu")
			(hatch none 0.5)
			(connect_pads
				(clearance 0)
			)
			(min_thickness 0.25)
			(keepout
				(tracks allowed)
				(vias not_allowed)
				(pads allowed)
				(copperpour not_allowed)
				(footprints allowed)
			)
			(placement
				(enabled no)
				(sheetname "")
			)
			(fill
				(thermal_gap 0.5)
				(thermal_bridge_width 0.5)
				(island_removal_mode 0)
			)
			(polygon
				(pts
					(xy 367.573814 -124.135642) (xy 367.573814 -124.643642) (xy 367.192814 -124.643642) (xy 367.192814 -124.135642)
				)
			)
		)
	)
	(footprint ""
		(layer "B.Cu")
		(at 2.1082 -50.1142 -90)
		(property "Reference" "C9R12"
			(at 0 0 90)
			(layer "B.SilkS")
			(hide yes)
			(effects
				(font
					(size 1.27 1.27)
				)
				(justify mirror)
			)
		)
		(property "Value" ""
			(at 0 0 90)
			(layer "B.Fab")
			(effects
				(font
					(size 1.27 1.27)
				)
				(justify mirror)
			)
		)
		(duplicate_pad_numbers_are_jumpers no)
		(fp_rect
			(start 0.3048 -0.1016)
			(end -0.3048 0.9906)
			(stroke
				(width 0)
				(type default)
			)
			(fill no)
			(layer "B.CrtYd")
		)
		(fp_line
			(start -0.3048 0.9906)
			(end -0.3048 -0.1016)
			(stroke
				(width 0.1)
				(type default)
			)
			(layer "B.Fab")
		)
		(fp_line
			(start 0.3048 0.9906)
			(end -0.3048 0.9906)
			(stroke
				(width 0.1)
				(type default)
			)
			(layer "B.Fab")
		)
		(fp_line
			(start -0.3048 -0.1016)
			(end 0.3048 -0.1016)
			(stroke
				(width 0.1)
				(type default)
			)
			(layer "B.Fab")
		)
		(fp_line
			(start 0.3048 -0.1016)
			(end 0.3048 0.9906)
			(stroke
				(width 0.1)
				(type default)
			)
			(layer "B.Fab")
		)
		(pad "1" smd rect
			(at 0 0 90)
			(size 0.508 0.508)
			(layers "B.Cu" "B.Mask" "B.Paste")
			(net "P12V_PSU")
		)
		(pad "2" smd rect
			(at 0 0.889 90)
			(size 0.508 0.508)
			(layers "B.Cu" "B.Mask" "B.Paste")
			(net "GND")
		)
		(zone
			(layer "B.Cu")
			(hatch none 0.5)
			(connect_pads
				(clearance 0)
			)
			(min_thickness 0.25)
			(keepout
				(tracks not_allowed)
				(vias allowed)
				(pads allowed)
				(copperpour not_allowed)
				(footprints allowed)
			)
			(placement
				(enabled no)
				(sheetname "")
			)
			(fill
				(thermal_gap 0.5)
				(thermal_bridge_width 0.5)
				(island_removal_mode 0)
			)
			(polygon
				(pts
					(xy 1.8542 -49.8602) (xy 1.8542 -50.3682) (xy 1.4732 -50.3682) (xy 1.4732 -49.8602)
				)
			)
		)
		(zone
			(layer "B.Cu")
			(hatch none 0.5)
			(connect_pads
				(clearance 0)
			)
			(min_thickness 0.25)
			(keepout
				(tracks allowed)
				(vias not_allowed)
				(pads allowed)
				(copperpour not_allowed)
				(footprints allowed)
			)
			(placement
				(enabled no)
				(sheetname "")
			)
			(fill
				(thermal_gap 0.5)
				(thermal_bridge_width 0.5)
				(island_removal_mode 0)
			)
			(polygon
				(pts
					(xy 1.8542 -49.8602) (xy 1.8542 -50.3682) (xy 1.4732 -50.3682) (xy 1.4732 -49.8602)
				)
			)
		)
	)
)
